(kicad_pcb
	(version 20260206)
	(generator "pcbnew")
	(generator_version "10.0")
	(general
		(thickness 1.6)
		(legacy_teardrops no)
	)
	(paper "A4")
	(title_block
		(title "Bryce Canyon_R.DPB_16317-1_OCP.brd")
		(comment 1 "Bryce Canyon / footprints 483-489 of 2099")
	)
	(layers
		(0 "F.Cu" signal "TOP")
		(4 "In1.Cu" signal "L2GND")
		(6 "In2.Cu" signal "L3")
		(8 "In3.Cu" signal "L4VCC")
		(10 "In4.Cu" signal "L5VCC")
		(12 "In5.Cu" signal "L6")
		(14 "In6.Cu" signal "L7GND")
		(2 "B.Cu" signal "BOTTOM")
		(9 "F.Adhes" user "F.Adhesive")
		(11 "B.Adhes" user "B.Adhesive")
		(13 "F.Paste" user "Package Geometry/Pastemask Top")
		(15 "B.Paste" user "Package Geometry/Pastemask Bottom")
		(5 "F.SilkS" user "Ref Des/Silkscreen Top")
		(7 "B.SilkS" user "Ref Des/Silkscreen Bottom")
		(1 "F.Mask" user "Board Geometry/Soldermask Top")
		(3 "B.Mask" user "Board Geometry/Soldermask Bottom")
		(17 "Dwgs.User" user "User.Drawings")
		(19 "Cmts.User" user "User.Comments")
		(21 "Eco1.User" user "User.Eco1")
		(23 "Eco2.User" user "User.Eco2")
		(25 "Edge.Cuts" user "Board Geometry/Outline")
		(27 "Margin" user)
		(31 "F.CrtYd" user "Package Geometry/Place Bound Top")
		(29 "B.CrtYd" user "Package Geometry/Place Bound Bottom")
		(35 "F.Fab" user "Ref Des/Assembly Top")
		(33 "B.Fab" user "Ref Des/Assembly Bottom")
	)
	(footprint ""
		(layer "F.Cu")
		(at 248.285 -306.07 -90)
		(property "Reference" "R1087"
			(at 0 0 270)
			(layer "F.SilkS")
			(hide yes)
			(effects
				(font
					(size 1.27 1.27)
				)
			)
		)
		(property "Value" "4K7R2F-GP"
			(at 0.064008 -3.993896 270)
			(unlocked yes)
			(layer "F.Fab")
			(hide yes)
			(effects
				(font
					(size 1.016 1.016)
					(thickness 0.1524)
				)
			)
		)
		(property "Device Type" "R402H16"
			(at 0.064008 -5.517896 270)
			(unlocked yes)
			(layer "F.Fab")
			(hide yes)
			(effects
				(font
					(size 1.016 1.016)
					(thickness 0.1524)
				)
			)
		)
		(duplicate_pad_numbers_are_jumpers no)
		(fp_line
			(start -0.508 -0.9398)
			(end -0.508 0.9398)
			(stroke
				(width 0.1524)
				(type default)
			)
			(layer "F.SilkS")
		)
		(fp_line
			(start 0.508 -0.9398)
			(end -0.508 -0.9398)
			(stroke
				(width 0.1524)
				(type default)
			)
			(layer "F.SilkS")
		)
		(fp_rect
			(start -0.508 0.9398)
			(end 0.508 -0.9398)
			(stroke
				(width 0)
				(type default)
			)
			(fill no)
			(layer "F.CrtYd")
		)
		(fp_rect
			(start -0.508 0.9398)
			(end 0.508 -0.9398)
			(stroke
				(width 0)
				(type default)
			)
			(fill no)
			(layer "F.Fab")
		)
		(pad "1" smd custom
			(at 0 -0.4445 270)
			(size 0.1397 0.1397)
			(layers "F.Cu" "F.Mask" "F.Paste")
			(net "P3V3_STBY_A")
			(options
				(clearance outline)
				(anchor circle)
			)
			(primitives
				(gr_poly
					(pts
						(arc
							(start -0.1778 -0.2794)
							(mid -0.249642 -0.249642)
							(end -0.2794 -0.1778)
						)
						(arc
							(start -0.2794 0.1778)
							(mid -0.249642 0.249642)
							(end -0.1778 0.2794)
						)
						(arc
							(start 0.1778 0.2794)
							(mid 0.249642 0.249642)
							(end 0.2794 0.1778)
						)
						(arc
							(start 0.2794 -0.1778)
							(mid 0.249642 -0.249642)
							(end 0.1778 -0.2794)
						)
					)
					(width 0)
					(fill yes)
				)
			)
		)
		(pad "2" smd custom
			(at 0 0.4445 270)
			(size 0.1397 0.1397)
			(layers "F.Cu" "F.Mask" "F.Paste")
			(net "MAX31790_A_FAIL")
			(options
				(clearance outline)
				(anchor circle)
			)
			(primitives
				(gr_poly
					(pts
						(arc
							(start -0.1778 -0.2794)
							(mid -0.249642 -0.249642)
							(end -0.2794 -0.1778)
						)
						(arc
							(start -0.2794 0.1778)
							(mid -0.249642 0.249642)
							(end -0.1778 0.2794)
						)
						(arc
							(start 0.1778 0.2794)
							(mid 0.249642 0.249642)
							(end 0.2794 0.1778)
						)
						(arc
							(start 0.2794 -0.1778)
							(mid 0.249642 -0.249642)
							(end 0.1778 -0.2794)
						)
					)
					(width 0)
					(fill yes)
				)
			)
		)
	)
	(footprint ""
		(layer "F.Cu")
		(at 180.1368 -246.2784 -90)
		(property "Reference" "R246"
			(at 0 0 270)
			(layer "F.SilkS")
			(hide yes)
			(effects
				(font
					(size 1.27 1.27)
				)
			)
		)
		(property "Value" "0R2J-2-GP"
			(at 0.064008 -3.993896 270)
			(unlocked yes)
			(layer "F.Fab")
			(hide yes)
			(effects
				(font
					(size 1.016 1.016)
					(thickness 0.1524)
				)
			)
		)
		(property "Device Type" "R402H16"
			(at 0.064008 -5.517896 270)
			(unlocked yes)
			(layer "F.Fab")
			(hide yes)
			(effects
				(font
					(size 1.016 1.016)
					(thickness 0.1524)
				)
			)
		)
		(duplicate_pad_numbers_are_jumpers no)
		(fp_line
			(start -0.508 -0.9398)
			(end -0.508 0.9398)
			(stroke
				(width 0.1524)
				(type default)
			)
			(layer "F.SilkS")
		)
		(fp_line
			(start 0.508 -0.9398)
			(end -0.508 -0.9398)
			(stroke
				(width 0.1524)
				(type default)
			)
			(layer "F.SilkS")
		)
		(fp_rect
			(start -0.508 0.9398)
			(end 0.508 -0.9398)
			(stroke
				(width 0)
				(type default)
			)
			(fill no)
			(layer "F.CrtYd")
		)
		(fp_rect
			(start -0.508 0.9398)
			(end 0.508 -0.9398)
			(stroke
				(width 0)
				(type default)
			)
			(fill no)
			(layer "F.Fab")
		)
		(pad "1" smd custom
			(at 0 -0.4445 270)
			(size 0.1397 0.1397)
			(layers "F.Cu" "F.Mask" "F.Paste")
			(net "DRIVE_B_5_PWR")
			(options
				(clearance outline)
				(anchor circle)
			)
			(primitives
				(gr_poly
					(pts
						(arc
							(start -0.1778 -0.2794)
							(mid -0.249642 -0.249642)
							(end -0.2794 -0.1778)
						)
						(arc
							(start -0.2794 0.1778)
							(mid -0.249642 0.249642)
							(end -0.1778 0.2794)
						)
						(arc
							(start 0.1778 0.2794)
							(mid 0.249642 0.249642)
							(end 0.2794 0.1778)
						)
						(arc
							(start 0.2794 -0.1778)
							(mid 0.249642 -0.249642)
							(end 0.1778 -0.2794)
						)
					)
					(width 0)
					(fill yes)
				)
			)
		)
		(pad "2" smd custom
			(at 0 0.4445 270)
			(size 0.1397 0.1397)
			(layers "F.Cu" "F.Mask" "F.Paste")
			(net "SW_PWR_R_HDD5")
			(options
				(clearance outline)
				(anchor circle)
			)
			(primitives
				(gr_poly
					(pts
						(arc
							(start -0.1778 -0.2794)
							(mid -0.249642 -0.249642)
							(end -0.2794 -0.1778)
						)
						(arc
							(start -0.2794 0.1778)
							(mid -0.249642 0.249642)
							(end -0.1778 0.2794)
						)
						(arc
							(start 0.1778 0.2794)
							(mid 0.249642 0.249642)
							(end 0.2794 0.1778)
						)
						(arc
							(start 0.2794 -0.1778)
							(mid 0.249642 -0.249642)
							(end 0.1778 -0.2794)
						)
					)
					(width 0)
					(fill yes)
				)
			)
		)
	)
	(footprint ""
		(layer "F.Cu")
		(at 458.47 -266.827 180)
		(property "Reference" "C161"
			(at 0 0 180)
			(layer "F.SilkS")
			(hide yes)
			(effects
				(font
					(size 1.27 1.27)
				)
			)
		)
		(property "Value" "SC10U16V6KX-2GP"
			(at -0.0762 -5.1308 180)
			(unlocked yes)
			(layer "F.Fab")
			(hide yes)
			(effects
				(font
					(size 1.016 1.016)
					(thickness 0.1524)
				)
			)
		)
		(property "Device Type" "C1206H71"
			(at -0.127 -6.6548 180)
			(unlocked yes)
			(layer "F.Fab")
			(hide yes)
			(effects
				(font
					(size 1.016 1.016)
					(thickness 0.1524)
				)
			)
		)
		(duplicate_pad_numbers_are_jumpers no)
		(fp_line
			(start 1.016 2.2352)
			(end -1.016 2.2352)
			(stroke
				(width 0.1524)
				(type default)
			)
			(layer "F.SilkS")
		)
		(fp_line
			(start 1.016 0.8382)
			(end 1.016 2.2352)
			(stroke
				(width 0.1524)
				(type default)
			)
			(layer "F.SilkS")
		)
		(fp_line
			(start 1.016 -2.2352)
			(end 1.016 -0.8382)
			(stroke
				(width 0.1524)
				(type default)
			)
			(layer "F.SilkS")
		)
		(fp_line
			(start -1.016 2.2352)
			(end -1.016 0.8382)
			(stroke
				(width 0.1524)
				(type default)
			)
			(layer "F.SilkS")
		)
		(fp_line
			(start -1.016 -0.8382)
			(end -1.016 -2.2352)
			(stroke
				(width 0.1524)
				(type default)
			)
			(layer "F.SilkS")
		)
		(fp_line
			(start -1.016 -2.2352)
			(end 1.016 -2.2352)
			(stroke
				(width 0.1524)
				(type default)
			)
			(layer "F.SilkS")
		)
		(fp_rect
			(start -1.0922 2.3114)
			(end 1.0922 -2.3114)
			(stroke
				(width 0)
				(type default)
			)
			(fill no)
			(layer "F.CrtYd")
		)
		(fp_poly
			(pts
				(xy 1.0922 -2.3114) (xy 1.0922 2.3114) (xy -1.0922 2.3114) (xy -1.0922 -2.3114)
			)
			(stroke
				(width 0)
				(type default)
			)
			(fill no)
			(layer "F.Fab")
		)
		(pad "1" smd rect
			(at 0 -1.397 180)
			(size 1.651 1.27)
			(layers "F.Cu" "F.Mask" "F.Paste")
			(net "P5V_HDD10")
		)
		(pad "2" smd rect
			(at 0 1.397 180)
			(size 1.651 1.27)
			(layers "F.Cu" "F.Mask" "F.Paste")
			(net "GND")
		)
	)
	(footprint ""
		(layer "F.Cu")
		(at 14.859 -140.462 90)
		(property "Reference" "C195"
			(at 0 0 90)
			(layer "F.SilkS")
			(hide yes)
			(effects
				(font
					(size 1.27 1.27)
				)
			)
		)
		(property "Value" "SCD033U25V2KX-GP"
			(at 1.1811 -2.7051 90)
			(unlocked yes)
			(layer "F.Fab")
			(hide yes)
			(effects
				(font
					(size 1.016 1.016)
					(thickness 0.1524)
				)
			)
		)
		(property "Device Type" "C402H22"
			(at 1.1811 -4.2291 90)
			(unlocked yes)
			(layer "F.Fab")
			(hide yes)
			(effects
				(font
					(size 1.016 1.016)
					(thickness 0.1524)
				)
			)
		)
		(duplicate_pad_numbers_are_jumpers no)
		(fp_rect
			(start -0.4318 0.9525)
			(end 0.4318 -0.9525)
			(stroke
				(width 0)
				(type default)
			)
			(fill no)
			(layer "F.CrtYd")
		)
		(fp_rect
			(start -0.4318 0.9525)
			(end 0.4318 -0.9525)
			(stroke
				(width 0)
				(type default)
			)
			(fill no)
			(layer "F.Fab")
		)
		(pad "1" smd custom
			(at 0 -0.4445 90)
			(size 0.1524 0.1524)
			(layers "F.Cu" "F.Mask" "F.Paste")
			(net "P12V_B")
			(options
				(clearance outline)
				(anchor circle)
			)
			(primitives
				(gr_poly
					(pts
						(arc
							(start 0.3048 -0.2032)
							(mid 0.275042 -0.275042)
							(end 0.2032 -0.3048)
						)
						(arc
							(start -0.2032 -0.3048)
							(mid -0.275042 -0.275042)
							(end -0.3048 -0.2032)
						)
						(arc
							(start -0.3048 0.2032)
							(mid -0.275042 0.275042)
							(end -0.2032 0.3048)
						)
						(arc
							(start 0.2032 0.3048)
							(mid 0.275042 0.275042)
							(end 0.3048 0.2032)
						)
					)
					(width 0)
					(fill yes)
				)
			)
		)
		(pad "2" smd custom
			(at 0 0.4445 90)
			(size 0.1524 0.1524)
			(layers "F.Cu" "F.Mask" "F.Paste")
			(net "SW_HDD_N12")
			(options
				(clearance outline)
				(anchor circle)
			)
			(primitives
				(gr_poly
					(pts
						(arc
							(start 0.3048 -0.2032)
							(mid 0.275042 -0.275042)
							(end 0.2032 -0.3048)
						)
						(arc
							(start -0.2032 -0.3048)
							(mid -0.275042 -0.275042)
							(end -0.3048 -0.2032)
						)
						(arc
							(start -0.3048 0.2032)
							(mid -0.275042 0.275042)
							(end -0.2032 0.3048)
						)
						(arc
							(start 0.2032 0.3048)
							(mid 0.275042 0.275042)
							(end 0.3048 0.2032)
						)
					)
					(width 0)
					(fill yes)
				)
			)
		)
	)
	(footprint ""
		(layer "F.Cu")
		(at 329.278996 -364.998 180)
		(property "Reference" "R948"
			(at 0 0 180)
			(layer "F.SilkS")
			(hide yes)
			(effects
				(font
					(size 1.27 1.27)
				)
			)
		)
		(property "Value" "4K7R2F-GP"
			(at 0.064008 -3.993896 180)
			(unlocked yes)
			(layer "F.Fab")
			(hide yes)
			(effects
				(font
					(size 1.016 1.016)
					(thickness 0.1524)
				)
			)
		)
		(property "Device Type" "R402H16"
			(at 0.064008 -5.517896 180)
			(unlocked yes)
			(layer "F.Fab")
			(hide yes)
			(effects
				(font
					(size 1.016 1.016)
					(thickness 0.1524)
				)
			)
		)
		(duplicate_pad_numbers_are_jumpers no)
		(fp_line
			(start 0.508 -0.9398)
			(end -0.508 -0.9398)
			(stroke
				(width 0.1524)
				(type default)
			)
			(layer "F.SilkS")
		)
		(fp_line
			(start -0.508 -0.9398)
			(end -0.508 0.9398)
			(stroke
				(width 0.1524)
				(type default)
			)
			(layer "F.SilkS")
		)
		(fp_rect
			(start -0.508 0.9398)
			(end 0.508 -0.9398)
			(stroke
				(width 0)
				(type default)
			)
			(fill no)
			(layer "F.CrtYd")
		)
		(fp_rect
			(start -0.508 0.9398)
			(end 0.508 -0.9398)
			(stroke
				(width 0)
				(type default)
			)
			(fill no)
			(layer "F.Fab")
		)
		(pad "1" smd custom
			(at 0 -0.4445 180)
			(size 0.1397 0.1397)
			(layers "F.Cu" "F.Mask" "F.Paste")
			(net "P12V_IN")
			(options
				(clearance outline)
				(anchor circle)
			)
			(primitives
				(gr_poly
					(pts
						(arc
							(start -0.1778 -0.2794)
							(mid -0.249642 -0.249642)
							(end -0.2794 -0.1778)
						)
						(arc
							(start -0.2794 0.1778)
							(mid -0.249642 0.249642)
							(end -0.1778 0.2794)
						)
						(arc
							(start 0.1778 0.2794)
							(mid 0.249642 0.249642)
							(end 0.2794 0.1778)
						)
						(arc
							(start 0.2794 -0.1778)
							(mid 0.249642 -0.249642)
							(end 0.1778 -0.2794)
						)
					)
					(width 0)
					(fill yes)
				)
			)
		)
		(pad "2" smd custom
			(at 0 0.4445 180)
			(size 0.1397 0.1397)
			(layers "F.Cu" "F.Mask" "F.Paste")
			(net "FAN_2_TACH1")
			(options
				(clearance outline)
				(anchor circle)
			)
			(primitives
				(gr_poly
					(pts
						(arc
							(start -0.1778 -0.2794)
							(mid -0.249642 -0.249642)
							(end -0.2794 -0.1778)
						)
						(arc
							(start -0.2794 0.1778)
							(mid -0.249642 0.249642)
							(end -0.1778 0.2794)
						)
						(arc
							(start 0.1778 0.2794)
							(mid 0.249642 0.249642)
							(end 0.2794 0.1778)
						)
						(arc
							(start 0.2794 -0.1778)
							(mid 0.249642 -0.249642)
							(end 0.1778 -0.2794)
						)
					)
					(width 0)
					(fill yes)
				)
			)
		)
	)
	(footprint ""
		(layer "F.Cu")
		(at 395.351 -23.368 180)
		(property "Reference" "Q165"
			(at 0 0 180)
			(layer "F.SilkS")
			(hide yes)
			(effects
				(font
					(size 1.27 1.27)
				)
			)
		)
		(property "Value" "AO4406AL-GP"
			(at -3.707384 -1.5367 180)
			(unlocked yes)
			(layer "F.Fab")
			(hide yes)
			(effects
				(font
					(size 1.016 1.016)
					(thickness 0.1524)
				)
			)
		)
		(property "Device Type" "SOIC8H69"
			(at -3.707384 -3.0607 180)
			(unlocked yes)
			(layer "F.Fab")
			(hide yes)
			(effects
				(font
					(size 1.016 1.016)
					(thickness 0.1524)
				)
			)
		)
		(duplicate_pad_numbers_are_jumpers no)
		(fp_line
			(start 2.1336 1.4224)
			(end 2.1336 -1.4224)
			(stroke
				(width 0.1524)
				(type default)
			)
			(layer "F.SilkS")
		)
		(fp_line
			(start 2.1336 -1.4224)
			(end -2.7432 -1.4224)
			(stroke
				(width 0.1524)
				(type default)
			)
			(layer "F.SilkS")
		)
		(fp_line
			(start -2.1844 -0.0508)
			(end -2.7178 0.508)
			(stroke
				(width 0.1524)
				(type default)
			)
			(layer "F.SilkS")
		)
		(fp_line
			(start -2.6289 3.4417)
			(end -2.6289 1.4732)
			(stroke
				(width 0.381)
				(type default)
			)
			(layer "F.SilkS")
		)
		(fp_line
			(start -2.7178 -0.508)
			(end -2.1844 -0.0508)
			(stroke
				(width 0.1524)
				(type default)
			)
			(layer "F.SilkS")
		)
		(fp_line
			(start -2.7432 1.4224)
			(end 2.1336 1.4224)
			(stroke
				(width 0.1524)
				(type default)
			)
			(layer "F.SilkS")
		)
		(fp_line
			(start -2.7432 1.4224)
			(end -2.6416 1.4224)
			(stroke
				(width 0.1524)
				(type default)
			)
			(layer "F.SilkS")
		)
		(fp_line
			(start -2.7432 -1.4224)
			(end -2.7432 1.4224)
			(stroke
				(width 0.1524)
				(type default)
			)
			(layer "F.SilkS")
		)
		(fp_poly
			(pts
				(xy -2.2098 -1.4224) (xy -2.2098 1.4224) (xy 2.2098 1.4224) (xy 2.2098 -1.4224)
			)
			(stroke
				(width 0)
				(type default)
			)
			(fill yes)
			(layer "F.SilkS")
		)
		(fp_rect
			(start -2.450084 2.999994)
			(end 2.450084 -2.999994)
			(stroke
				(width 0)
				(type default)
			)
			(fill no)
			(layer "F.CrtYd")
		)
		(fp_poly
			(pts
				(xy -2.8194 3.6322) (xy -2.8194 -3.6322) (xy 2.8194 -3.6322) (xy 2.8194 1.18364) (xy 2.450084 1.18364)
				(xy 2.450084 -2.999994) (xy -2.450084 -2.999994) (xy -2.450084 2.999994) (xy 2.450084 2.999994)
				(xy 2.450084 1.18618) (xy 2.8194 1.18618) (xy 2.8194 3.6322)
			)
			(stroke
				(width 0)
				(type default)
			)
			(fill no)
			(layer "F.CrtYd")
		)
		(fp_rect
			(start -2.8194 3.6322)
			(end 2.8194 -3.6322)
			(stroke
				(width 0)
				(type default)
			)
			(fill no)
			(layer "F.Fab")
		)
		(pad "1" smd rect
			(at -1.905 2.54 180)
			(size 0.635 1.651)
			(layers "F.Cu" "F.Mask" "F.Paste")
			(net "P5V_HDD32")
		)
		(pad "2" smd rect
			(at -0.635 2.54 180)
			(size 0.635 1.651)
			(layers "F.Cu" "F.Mask" "F.Paste")
			(net "P5V_HDD32")
		)
		(pad "3" smd rect
			(at 0.635 2.54 180)
			(size 0.635 1.651)
			(layers "F.Cu" "F.Mask" "F.Paste")
			(net "P5V_HDD32")
		)
		(pad "4" smd rect
			(at 1.905 2.54 180)
			(size 0.635 1.651)
			(layers "F.Cu" "F.Mask" "F.Paste")
			(net "SW_HDD_P32")
		)
		(pad "5" smd rect
			(at 1.905 -2.54 180)
			(size 0.635 1.651)
			(layers "F.Cu" "F.Mask" "F.Paste")
			(net "P5V_B_4")
		)
		(pad "6" smd rect
			(at 0.635 -2.54 180)
			(size 0.635 1.651)
			(layers "F.Cu" "F.Mask" "F.Paste")
			(net "P5V_B_4")
		)
		(pad "7" smd rect
			(at -0.635 -2.54 180)
			(size 0.635 1.651)
			(layers "F.Cu" "F.Mask" "F.Paste")
			(net "P5V_B_4")
		)
		(pad "8" smd rect
			(at -1.905 -2.54 180)
			(size 0.635 1.651)
			(layers "F.Cu" "F.Mask" "F.Paste")
			(net "P5V_B_4")
		)
	)
	(footprint ""
		(layer "F.Cu")
		(at 386.41655 -17.4371)
		(property "Reference" "VIA66"
			(at 0 0 0)
			(layer "F.SilkS")
			(hide yes)
			(effects
				(font
					(size 1.27 1.27)
				)
			)
		)
		(property "Value" "100OHM-8L-2D36MM-L16-GP"
			(at -3.4036 -0.4572 0)
			(unlocked yes)
			(layer "F.Fab")
			(hide yes)
			(effects
				(font
					(size 1.016 1.016)
					(thickness 0.1524)
				)
			)
		)
		(property "Device Type" "VIA-PCIE-4P-427097"
			(at -3.4036 -1.9812 0)
			(unlocked yes)
			(layer "F.Fab")
			(hide yes)
			(effects
				(font
					(size 1.016 1.016)
					(thickness 0.1524)
				)
			)
		)
		(duplicate_pad_numbers_are_jumpers no)
		(fp_rect
			(start -2.1336 0.4826)
			(end 2.1336 -0.4826)
			(stroke
				(width 0)
				(type default)
			)
			(fill no)
			(layer "F.CrtYd")
		)
		(fp_rect
			(start -2.1336 0.4826)
			(end 2.1336 -0.4826)
			(stroke
				(width 0)
				(type default)
			)
			(fill no)
			(layer "F.Fab")
		)
		(pad "1" thru_hole circle
			(at -1.651 0)
			(size 0.508 0.508)
			(drill 0.254)
			(layers "*.Cu" "*.Mask")
			(remove_unused_layers no)
			(net "GND")
			(clearance 0.2286)
			(thermal_gap 0.2286)
		)
		(pad "2" thru_hole circle
			(at -0.635 0)
			(size 0.508 0.508)
			(drill 0.254)
			(layers "*.Cu" "*.Mask")
			(remove_unused_layers no)
			(net "PHY_DRV_B_TO_SCC_B_32_DP")
			(clearance 0.2286)
			(thermal_gap 0.2286)
		)
		(pad "3" thru_hole circle
			(at 0.635 0)
			(size 0.508 0.508)
			(drill 0.254)
			(layers "*.Cu" "*.Mask")
			(remove_unused_layers no)
			(net "PHY_DRV_B_TO_SCC_B_32_DN")
			(clearance 0.2286)
			(thermal_gap 0.2286)
		)
		(pad "4" thru_hole circle
			(at 1.651 0)
			(size 0.508 0.508)
			(drill 0.254)
			(layers "*.Cu" "*.Mask")
			(remove_unused_layers no)
			(net "GND")
			(clearance 0.2286)
			(thermal_gap 0.2286)
		)
	)
)
